# SCM (Grand Teton) — schematic netlist excerpt (pin names and nets, part order shuffled) for the footprints in the layout excerpt that follows; sources: Cadence DE-HDL packaged netlist, KiCad conversion of 12092022_DA0F0TMDCD0_F0T_Management_Board_D_brd_V3_OCP.brd

R207  Q_RES  0 5% CHIP  pkg 0402LF  page 15 : A = P3V3_AUX ; B = P3V3_P1V8_SD1VDD
C136  Q_CAP  0.01UF 50V 10% X7R  pkg C0402  page 17 : A = GND ; B = A_BMC_ADCVREFP0

(kicad_pcb
	(version 20260206)
	(generator "pcbnew")
	(generator_version "10.0")
	(general
		(thickness 1.6)
		(legacy_teardrops no)
	)
	(paper "A4")
	(title_block
		(title "12092022_DA0F0TMDCD0_F0T_Management_Board_D_brd_V3_OCP.brd")
		(comment 1 "Grand Teton / footprints 1084-1085 of 1440")
	)
	(layers
		(0 "F.Cu" signal "TOP")
		(4 "In1.Cu" signal "GND")
		(6 "In2.Cu" signal "IN1")
		(8 "In3.Cu" signal "GND1")
		(10 "In4.Cu" signal "IN2")
		(12 "In5.Cu" signal "VCC")
		(14 "In6.Cu" signal "VCC1")
		(16 "In7.Cu" signal "IN3")
		(18 "In8.Cu" signal "GND2")
		(20 "In9.Cu" signal "IN4")
		(22 "In10.Cu" signal "GND3")
		(2 "B.Cu" signal "BOTTOM")
		(9 "F.Adhes" user "F.Adhesive")
		(11 "B.Adhes" user "B.Adhesive")
		(13 "F.Paste" user "Package Geometry/Pastemask Top")
		(15 "B.Paste" user "Package Geometry/Pastemask Bottom")
		(5 "F.SilkS" user "Ref Des/Silkscreen Top")
		(7 "B.SilkS" user "Ref Des/Silkscreen Bottom")
		(1 "F.Mask" user "Board Geometry/Soldermask Top")
		(3 "B.Mask" user "Board Geometry/Soldermask Bottom")
		(17 "Dwgs.User" user "User.Drawings")
		(19 "Cmts.User" user "User.Comments")
		(21 "Eco1.User" user "User.Eco1")
		(23 "Eco2.User" user "User.Eco2")
		(25 "Edge.Cuts" user "Board Geometry/Outline")
		(27 "Margin" user)
		(31 "F.CrtYd" user "Package Geometry/Place Bound Top")
		(29 "B.CrtYd" user "Package Geometry/Place Bound Bottom")
		(35 "F.Fab" user "Ref Des/Assembly Top")
		(33 "B.Fab" user "Ref Des/Assembly Bottom")
	)
	(footprint ""
		(layer "B.Cu")
		(at 37.311076 -38.822376 180)
		(property "Reference" "R207"
			(at 0 0 0)
			(layer "B.SilkS")
			(hide yes)
			(effects
				(font
					(size 1.27 1.27)
				)
				(justify mirror)
			)
		)
		(property "Value" ""
			(at 0 0 0)
			(layer "B.Fab")
			(effects
				(font
					(size 1.27 1.27)
				)
				(justify mirror)
			)
		)
		(duplicate_pad_numbers_are_jumpers no)
		(fp_line
			(start 0.7874 0.4064)
			(end 0.7874 -0.4064)
			(stroke
				(width 0.1524)
				(type default)
			)
			(layer "B.SilkS")
		)
		(fp_line
			(start 0.7874 -0.4064)
			(end -0.7874 -0.4064)
			(stroke
				(width 0.1524)
				(type default)
			)
			(layer "B.SilkS")
		)
		(fp_line
			(start -0.7874 0.4064)
			(end 0.7874 0.4064)
			(stroke
				(width 0.1524)
				(type default)
			)
			(layer "B.SilkS")
		)
		(fp_line
			(start -0.7874 -0.4064)
			(end -0.7874 0.4064)
			(stroke
				(width 0.1524)
				(type default)
			)
			(layer "B.SilkS")
		)
		(fp_line
			(start 0.67945 0.3048)
			(end 0.67945 -0.305054)
			(stroke
				(width 0.1)
				(type default)
			)
			(layer "B.Fab")
		)
		(fp_line
			(start 0.67945 -0.305054)
			(end 0.12065 -0.305054)
			(stroke
				(width 0.1)
				(type default)
			)
			(layer "B.Fab")
		)
		(fp_line
			(start 0.12065 0.3048)
			(end 0.67945 0.3048)
			(stroke
				(width 0.1)
				(type default)
			)
			(layer "B.Fab")
		)
		(fp_line
			(start 0.12065 0.2794)
			(end 0.12065 0.3048)
			(stroke
				(width 0.1)
				(type default)
			)
			(layer "B.Fab")
		)
		(fp_line
			(start 0.12065 -0.2794)
			(end -0.12065 -0.2794)
			(stroke
				(width 0.1)
				(type default)
			)
			(layer "B.Fab")
		)
		(fp_line
			(start 0.12065 -0.305054)
			(end 0.12065 -0.2794)
			(stroke
				(width 0.1)
				(type default)
			)
			(layer "B.Fab")
		)
		(fp_line
			(start -0.120396 0.3048)
			(end -0.120396 0.2794)
			(stroke
				(width 0.1)
				(type default)
			)
			(layer "B.Fab")
		)
		(fp_line
			(start -0.120396 0.2794)
			(end 0.12065 0.2794)
			(stroke
				(width 0.1)
				(type default)
			)
			(layer "B.Fab")
		)
		(fp_line
			(start -0.12065 -0.2794)
			(end -0.12065 -0.3048)
			(stroke
				(width 0.1)
				(type default)
			)
			(layer "B.Fab")
		)
		(fp_line
			(start -0.12065 -0.3048)
			(end -0.67945 -0.3048)
			(stroke
				(width 0.1)
				(type default)
			)
			(layer "B.Fab")
		)
		(fp_line
			(start -0.67945 0.3048)
			(end -0.120396 0.3048)
			(stroke
				(width 0.1)
				(type default)
			)
			(layer "B.Fab")
		)
		(fp_line
			(start -0.67945 -0.3048)
			(end -0.67945 0.3048)
			(stroke
				(width 0.1)
				(type default)
			)
			(layer "B.Fab")
		)
		(pad "1" smd circle
			(at 0.40005 0)
			(size 0 0)
			(layers "B.Cu" "B.Mask" "B.Paste")
			(net "P3V3_AUX")
		)
		(pad "2" smd circle
			(at -0.40005 0)
			(size 0 0)
			(layers "B.Cu" "B.Mask" "B.Paste")
			(net "P3V3_P1V8_SD1VDD")
		)
	)
	(footprint ""
		(layer "B.Cu")
		(at 46.96206 -61.97981 90)
		(property "Reference" "C136"
			(at 0 0 90)
			(layer "B.SilkS")
			(hide yes)
			(effects
				(font
					(size 1.27 1.27)
				)
				(justify mirror)
			)
		)
		(property "Value" ""
			(at 0 0 90)
			(layer "B.Fab")
			(effects
				(font
					(size 1.27 1.27)
				)
				(justify mirror)
			)
		)
		(duplicate_pad_numbers_are_jumpers no)
		(fp_line
			(start 0.7874 -0.4064)
			(end -0.7874 -0.4064)
			(stroke
				(width 0.1524)
				(type default)
			)
			(layer "B.SilkS")
		)
		(fp_line
			(start -0.7874 -0.4064)
			(end -0.7874 0.4064)
			(stroke
				(width 0.1524)
				(type default)
			)
			(layer "B.SilkS")
		)
		(fp_line
			(start 0.7874 0.4064)
			(end 0.7874 -0.4064)
			(stroke
				(width 0.1524)
				(type default)
			)
			(layer "B.SilkS")
		)
		(fp_line
			(start -0.7874 0.4064)
			(end 0.7874 0.4064)
			(stroke
				(width 0.1524)
				(type default)
			)
			(layer "B.SilkS")
		)
		(fp_line
			(start 0.67945 -0.305054)
			(end 0.12065 -0.305054)
			(stroke
				(width 0.1)
				(type default)
			)
			(layer "B.Fab")
		)
		(fp_line
			(start 0.12065 -0.305054)
			(end 0.12065 -0.2794)
			(stroke
				(width 0.1)
				(type default)
			)
			(layer "B.Fab")
		)
		(fp_line
			(start -0.12065 -0.3048)
			(end -0.67945 -0.3048)
			(stroke
				(width 0.1)
				(type default)
			)
			(layer "B.Fab")
		)
		(fp_line
			(start -0.67945 -0.3048)
			(end -0.67945 0.3048)
			(stroke
				(width 0.1)
				(type default)
			)
			(layer "B.Fab")
		)
		(fp_line
			(start 0.12065 -0.2794)
			(end -0.12065 -0.2794)
			(stroke
				(width 0.1)
				(type default)
			)
			(layer "B.Fab")
		)
		(fp_line
			(start -0.12065 -0.2794)
			(end -0.12065 -0.3048)
			(stroke
				(width 0.1)
				(type default)
			)
			(layer "B.Fab")
		)
		(fp_line
			(start 0.12065 0.2794)
			(end 0.12065 0.3048)
			(stroke
				(width 0.1)
				(type default)
			)
			(layer "B.Fab")
		)
		(fp_line
			(start -0.120396 0.2794)
			(end 0.12065 0.2794)
			(stroke
				(width 0.1)
				(type default)
			)
			(layer "B.Fab")
		)
		(fp_line
			(start 0.67945 0.3048)
			(end 0.67945 -0.305054)
			(stroke
				(width 0.1)
				(type default)
			)
			(layer "B.Fab")
		)
		(fp_line
			(start 0.12065 0.3048)
			(end 0.67945 0.3048)
			(stroke
				(width 0.1)
				(type default)
			)
			(layer "B.Fab")
		)
		(fp_line
			(start -0.120396 0.3048)
			(end -0.120396 0.2794)
			(stroke
				(width 0.1)
				(type default)
			)
			(layer "B.Fab")
		)
		(fp_line
			(start -0.67945 0.3048)
			(end -0.120396 0.3048)
			(stroke
				(width 0.1)
				(type default)
			)
			(layer "B.Fab")
		)
		(pad "1" smd circle
			(at 0.40005 0 270)
			(size 0 0)
			(layers "B.Cu" "B.Mask" "B.Paste")
			(net "GND")
		)
		(pad "2" smd circle
			(at -0.40005 0 270)
			(size 0 0)
			(layers "B.Cu" "B.Mask" "B.Paste")
			(net "A_BMC_ADCVREFP0")
		)
	)
)
